(kicad_pcb
	(version 20260206)
	(generator "pcbnew")
	(generator_version "10.0")
	(general
		(thickness 1.6)
		(legacy_teardrops no)
	)
	(paper "A4")
	(title_block
		(title "Wiwynn_Tioga_Pass_MB.brd")
		(comment 1 "Tioga Pass / footprint 1253 of 4770 (EU7A5), pads 1-41 of 41")
	)
	(layers
		(0 "F.Cu" signal "TOP")
		(4 "In1.Cu" signal "L2GND")
		(6 "In2.Cu" signal "L3")
		(8 "In3.Cu" signal "L4GND")
		(10 "In4.Cu" signal "L5")
		(12 "In5.Cu" signal "L6GND")
		(14 "In6.Cu" signal "L7VCC")
		(16 "In7.Cu" signal "L8VCC")
		(18 "In8.Cu" signal "L9GND")
		(20 "In9.Cu" signal "L10")
		(22 "In10.Cu" signal "L11GND")
		(24 "In11.Cu" signal "L12")
		(26 "In12.Cu" signal "L13GND")
		(2 "B.Cu" signal "BOTTOM")
		(9 "F.Adhes" user "F.Adhesive")
		(11 "B.Adhes" user "B.Adhesive")
		(13 "F.Paste" user "Package Geometry/Pastemask Top")
		(15 "B.Paste" user "Package Geometry/Pastemask Bottom")
		(5 "F.SilkS" user "Ref Des/Silkscreen Top")
		(7 "B.SilkS" user "Ref Des/Silkscreen Bottom")
		(1 "F.Mask" user "Board Geometry/Soldermask Top")
		(3 "B.Mask" user "Board Geometry/Soldermask Bottom")
		(17 "Dwgs.User" user "User.Drawings")
		(19 "Cmts.User" user "User.Comments")
		(21 "Eco1.User" user "User.Eco1")
		(23 "Eco2.User" user "User.Eco2")
		(25 "Edge.Cuts" user "Board Geometry/Outline")
		(27 "Margin" user)
		(31 "F.CrtYd" user "Package Geometry/Place Bound Top")
		(29 "B.CrtYd" user "Package Geometry/Place Bound Bottom")
		(35 "F.Fab" user "Ref Des/Assembly Top")
		(33 "B.Fab" user "Ref Des/Assembly Bottom")
	)
	(footprint ""
		(layer "F.Cu")
		(at 359.29824 -138.16457 90)
		(property "Reference" "EU7A5"
			(at -1.51257 -3.29057 90)
			(unlocked yes)
			(layer "F.SilkS")
			(effects
				(font
					(size 0.7874 0.5842)
					(thickness 0.1524)
				)
				(justify left)
			)
		)
		(property "Value" ""
			(at 0 0 90)
			(layer "F.Fab")
			(effects
				(font
					(size 1.27 1.27)
				)
			)
		)
		(duplicate_pad_numbers_are_jumpers no)
		(pad "1" smd custom
			(at -2.4511 -1.800098 90)
			(size 0.0508 0.0508)
			(layers "F.Cu" "F.Mask" "F.Paste")
			(net "Net_283")
			(options
				(clearance outline)
				(anchor circle)
			)
			(primitives
				(gr_poly
					(pts
						(arc
							(start 0.254 -0.1016)
							(mid 0.3556 0)
							(end 0.254 0.1016)
						)
						(xy -0.3556 0.1016) (xy -0.3556 -0.1016)
					)
					(width 0)
					(fill yes)
				)
			)
		)
		(pad "2" smd custom
			(at -2.4511 -1.400048 90)
			(size 0.0508 0.0508)
			(layers "F.Cu" "F.Mask" "F.Paste")
			(net "Net_347")
			(options
				(clearance outline)
				(anchor circle)
			)
			(primitives
				(gr_poly
					(pts
						(arc
							(start 0.254 -0.1016)
							(mid 0.3556 0)
							(end 0.254 0.1016)
						)
						(xy -0.3556 0.1016) (xy -0.3556 -0.1016)
					)
					(width 0)
					(fill yes)
				)
			)
		)
		(pad "3" smd custom
			(at -2.4511 -0.999998 90)
			(size 0.0508 0.0508)
			(layers "F.Cu" "F.Mask" "F.Paste")
			(net "Net_245")
			(options
				(clearance outline)
				(anchor circle)
			)
			(primitives
				(gr_poly
					(pts
						(arc
							(start 0.254 -0.1016)
							(mid 0.3556 0)
							(end 0.254 0.1016)
						)
						(xy -0.3556 0.1016) (xy -0.3556 -0.1016)
					)
					(width 0)
					(fill yes)
				)
			)
		)
		(pad "4" smd custom
			(at -2.4511 -0.599948 90)
			(size 0.0508 0.0508)
			(layers "F.Cu" "F.Mask" "F.Paste")
			(net "VR_PVDDQ_DEF_PWM2")
			(options
				(clearance outline)
				(anchor circle)
			)
			(primitives
				(gr_poly
					(pts
						(arc
							(start 0.254 -0.1016)
							(mid 0.3556 0)
							(end 0.254 0.1016)
						)
						(xy -0.3556 0.1016) (xy -0.3556 -0.1016)
					)
					(width 0)
					(fill yes)
				)
			)
		)
		(pad "5" smd custom
			(at -2.4511 -0.199898 90)
			(size 0.0508 0.0508)
			(layers "F.Cu" "F.Mask" "F.Paste")
			(net "VR_PVDDQ_DEF_PWM1")
			(options
				(clearance outline)
				(anchor circle)
			)
			(primitives
				(gr_poly
					(pts
						(arc
							(start 0.254 -0.1016)
							(mid 0.3556 0)
							(end 0.254 0.1016)
						)
						(xy -0.3556 0.1016) (xy -0.3556 -0.1016)
					)
					(width 0)
					(fill yes)
				)
			)
		)
		(pad "6" smd custom
			(at -2.4511 0.199898 90)
			(size 0.0508 0.0508)
			(layers "F.Cu" "F.Mask" "F.Paste")
			(net "SMB_VR_STBY_LVC3_SDA")
			(options
				(clearance outline)
				(anchor circle)
			)
			(primitives
				(gr_poly
					(pts
						(arc
							(start 0.254 -0.1016)
							(mid 0.3556 0)
							(end 0.254 0.1016)
						)
						(xy -0.3556 0.1016) (xy -0.3556 -0.1016)
					)
					(width 0)
					(fill yes)
				)
			)
		)
		(pad "7" smd custom
			(at -2.4511 0.599948 90)
			(size 0.0508 0.0508)
			(layers "F.Cu" "F.Mask" "F.Paste")
			(net "SMB_VR_STBY_LVC3_SCL")
			(options
				(clearance outline)
				(anchor circle)
			)
			(primitives
				(gr_poly
					(pts
						(arc
							(start 0.254 -0.1016)
							(mid 0.3556 0)
							(end 0.254 0.1016)
						)
						(xy -0.3556 0.1016) (xy -0.3556 -0.1016)
					)
					(width 0)
					(fill yes)
				)
			)
		)
		(pad "8" smd custom
			(at -2.4511 0.999998 90)
			(size 0.0508 0.0508)
			(layers "F.Cu" "F.Mask" "F.Paste")
			(net "Net_284")
			(options
				(clearance outline)
				(anchor circle)
			)
			(primitives
				(gr_poly
					(pts
						(arc
							(start 0.254 -0.1016)
							(mid 0.3556 0)
							(end 0.254 0.1016)
						)
						(xy -0.3556 0.1016) (xy -0.3556 -0.1016)
					)
					(width 0)
					(fill yes)
				)
			)
		)
		(pad "9" smd custom
			(at -2.4511 1.400048 90)
			(size 0.0508 0.0508)
			(layers "F.Cu" "F.Mask" "F.Paste")
			(net "PWRGD_PVDDQ_DEF_R")
			(options
				(clearance outline)
				(anchor circle)
			)
			(primitives
				(gr_poly
					(pts
						(arc
							(start 0.254 -0.1016)
							(mid 0.3556 0)
							(end 0.254 0.1016)
						)
						(xy -0.3556 0.1016) (xy -0.3556 -0.1016)
					)
					(width 0)
					(fill yes)
				)
			)
		)
		(pad "10" smd custom
			(at -2.4511 1.800098 90)
			(size 0.0508 0.0508)
			(layers "F.Cu" "F.Mask" "F.Paste")
			(net "VR_PVDDQ_DEF_VREN")
			(options
				(clearance outline)
				(anchor circle)
			)
			(primitives
				(gr_poly
					(pts
						(arc
							(start 0.254 -0.1016)
							(mid 0.3556 0)
							(end 0.254 0.1016)
						)
						(xy -0.3556 0.1016) (xy -0.3556 -0.1016)
					)
					(width 0)
					(fill yes)
				)
			)
		)
		(pad "11" smd custom
			(at -1.800098 2.4511 90)
			(size 0.0508 0.0508)
			(layers "F.Cu" "F.Mask" "F.Paste")
			(net "IRQ_PVDDQ_DEF_VRHOT_LVT3_R_N")
			(options
				(clearance outline)
				(anchor circle)
			)
			(primitives
				(gr_poly
					(pts
						(arc
							(start -0.1016 -0.254)
							(mid 0 -0.3556)
							(end 0.1016 -0.254)
						)
						(xy 0.1016 0.3556) (xy -0.1016 0.3556)
					)
					(width 0)
					(fill yes)
				)
			)
		)
		(pad "12" smd custom
			(at -1.400048 2.4511 90)
			(size 0.0508 0.0508)
			(layers "F.Cu" "F.Mask" "F.Paste")
			(net "Net_230")
			(options
				(clearance outline)
				(anchor circle)
			)
			(primitives
				(gr_poly
					(pts
						(arc
							(start -0.1016 -0.254)
							(mid 0 -0.3556)
							(end 0.1016 -0.254)
						)
						(xy 0.1016 0.3556) (xy -0.1016 0.3556)
					)
					(width 0)
					(fill yes)
				)
			)
		)
		(pad "13" smd custom
			(at -0.999998 2.4511 90)
			(size 0.0508 0.0508)
			(layers "F.Cu" "F.Mask" "F.Paste")
			(net "PU_VR_PVDDQ_DEF_FAULT1")
			(options
				(clearance outline)
				(anchor circle)
			)
			(primitives
				(gr_poly
					(pts
						(arc
							(start -0.1016 -0.254)
							(mid 0 -0.3556)
							(end 0.1016 -0.254)
						)
						(xy 0.1016 0.3556) (xy -0.1016 0.3556)
					)
					(width 0)
					(fill yes)
				)
			)
		)
		(pad "14" smd custom
			(at -0.599948 2.4511 90)
			(size 0.0508 0.0508)
			(layers "F.Cu" "F.Mask" "F.Paste")
			(net "TP_PVDDQ_DEF_MP1")
			(options
				(clearance outline)
				(anchor circle)
			)
			(primitives
				(gr_poly
					(pts
						(arc
							(start -0.1016 -0.254)
							(mid 0 -0.3556)
							(end 0.1016 -0.254)
						)
						(xy 0.1016 0.3556) (xy -0.1016 0.3556)
					)
					(width 0)
					(fill yes)
				)
			)
		)
		(pad "15" smd custom
			(at -0.199898 2.4511 90)
			(size 0.0508 0.0508)
			(layers "F.Cu" "F.Mask" "F.Paste")
			(net "SVID_CLK_PVDDQ_DEF")
			(options
				(clearance outline)
				(anchor circle)
			)
			(primitives
				(gr_poly
					(pts
						(arc
							(start -0.1016 -0.254)
							(mid 0 -0.3556)
							(end 0.1016 -0.254)
						)
						(xy 0.1016 0.3556) (xy -0.1016 0.3556)
					)
					(width 0)
					(fill yes)
				)
			)
		)
		(pad "16" smd custom
			(at 0.199898 2.4511 90)
			(size 0.0508 0.0508)
			(layers "F.Cu" "F.Mask" "F.Paste")
			(net "SVID_VDIO_PVDDQ_DEF")
			(options
				(clearance outline)
				(anchor circle)
			)
			(primitives
				(gr_poly
					(pts
						(arc
							(start -0.1016 -0.254)
							(mid 0 -0.3556)
							(end 0.1016 -0.254)
						)
						(xy 0.1016 0.3556) (xy -0.1016 0.3556)
					)
					(width 0)
					(fill yes)
				)
			)
		)
		(pad "17" smd custom
			(at 0.599948 2.4511 90)
			(size 0.0508 0.0508)
			(layers "F.Cu" "F.Mask" "F.Paste")
			(net "SVID_ALERT_PVDDQ_DEF")
			(options
				(clearance outline)
				(anchor circle)
			)
			(primitives
				(gr_poly
					(pts
						(arc
							(start -0.1016 -0.254)
							(mid 0 -0.3556)
							(end 0.1016 -0.254)
						)
						(xy 0.1016 0.3556) (xy -0.1016 0.3556)
					)
					(width 0)
					(fill yes)
				)
			)
		)
		(pad "18" smd custom
			(at 0.999998 2.4511 90)
			(size 0.0508 0.0508)
			(layers "F.Cu" "F.Mask" "F.Paste")
			(net "TP_PVDDQ_DEF_MP2")
			(options
				(clearance outline)
				(anchor circle)
			)
			(primitives
				(gr_poly
					(pts
						(arc
							(start -0.1016 -0.254)
							(mid 0 -0.3556)
							(end 0.1016 -0.254)
						)
						(xy 0.1016 0.3556) (xy -0.1016 0.3556)
					)
					(width 0)
					(fill yes)
				)
			)
		)
		(pad "19" smd custom
			(at 1.400048 2.4511 90)
			(size 0.0508 0.0508)
			(layers "F.Cu" "F.Mask" "F.Paste")
			(net "VR_PVDDQ_DEF_AVSP")
			(options
				(clearance outline)
				(anchor circle)
			)
			(primitives
				(gr_poly
					(pts
						(arc
							(start -0.1016 -0.254)
							(mid 0 -0.3556)
							(end 0.1016 -0.254)
						)
						(xy 0.1016 0.3556) (xy -0.1016 0.3556)
					)
					(width 0)
					(fill yes)
				)
			)
		)
		(pad "20" smd custom
			(at 1.800098 2.4511 90)
			(size 0.0508 0.0508)
			(layers "F.Cu" "F.Mask" "F.Paste")
			(net "VSENSE_PVDDQ_DEF_N")
			(options
				(clearance outline)
				(anchor circle)
			)
			(primitives
				(gr_poly
					(pts
						(arc
							(start -0.1016 -0.254)
							(mid 0 -0.3556)
							(end 0.1016 -0.254)
						)
						(xy 0.1016 0.3556) (xy -0.1016 0.3556)
					)
					(width 0)
					(fill yes)
				)
			)
		)
		(pad "21" smd custom
			(at 2.4511 1.800098 90)
			(size 0.0508 0.0508)
			(layers "F.Cu" "F.Mask" "F.Paste")
			(net "VR_PVDDQ_DEF_AIREF1")
			(options
				(clearance outline)
				(anchor circle)
			)
			(primitives
				(gr_poly
					(pts
						(arc
							(start -0.254 0.1016)
							(mid -0.3556 0)
							(end -0.254 -0.1016)
						)
						(xy 0.3556 -0.1016) (xy 0.3556 0.1016)
					)
					(width 0)
					(fill yes)
				)
			)
		)
		(pad "22" smd custom
			(at 2.4511 1.400048 90)
			(size 0.0508 0.0508)
			(layers "F.Cu" "F.Mask" "F.Paste")
			(net "ISENSE_PVDDQ_DEF_PH1_IMON")
			(options
				(clearance outline)
				(anchor circle)
			)
			(primitives
				(gr_poly
					(pts
						(arc
							(start -0.254 0.1016)
							(mid -0.3556 0)
							(end -0.254 -0.1016)
						)
						(xy 0.3556 -0.1016) (xy 0.3556 0.1016)
					)
					(width 0)
					(fill yes)
				)
			)
		)
		(pad "23" smd custom
			(at 2.4511 0.999998 90)
			(size 0.0508 0.0508)
			(layers "F.Cu" "F.Mask" "F.Paste")
			(net "VR_PVDDQ_DEF_AIREF2")
			(options
				(clearance outline)
				(anchor circle)
			)
			(primitives
				(gr_poly
					(pts
						(arc
							(start -0.254 0.1016)
							(mid -0.3556 0)
							(end -0.254 -0.1016)
						)
						(xy 0.3556 -0.1016) (xy 0.3556 0.1016)
					)
					(width 0)
					(fill yes)
				)
			)
		)
		(pad "24" smd custom
			(at 2.4511 0.599948 90)
			(size 0.0508 0.0508)
			(layers "F.Cu" "F.Mask" "F.Paste")
			(net "ISENSE_PVDDQ_DEF_PH2_IMON")
			(options
				(clearance outline)
				(anchor circle)
			)
			(primitives
				(gr_poly
					(pts
						(arc
							(start -0.254 0.1016)
							(mid -0.3556 0)
							(end -0.254 -0.1016)
						)
						(xy 0.3556 -0.1016) (xy 0.3556 0.1016)
					)
					(width 0)
					(fill yes)
				)
			)
		)
		(pad "25" smd custom
			(at 2.4511 0.199898 90)
			(size 0.0508 0.0508)
			(layers "F.Cu" "F.Mask" "F.Paste")
			(net "Net_244")
			(options
				(clearance outline)
				(anchor circle)
			)
			(primitives
				(gr_poly
					(pts
						(arc
							(start -0.254 0.1016)
							(mid -0.3556 0)
							(end -0.254 -0.1016)
						)
						(xy 0.3556 -0.1016) (xy 0.3556 0.1016)
					)
					(width 0)
					(fill yes)
				)
			)
		)
		(pad "26" smd custom
			(at 2.4511 -0.199898 90)
			(size 0.0508 0.0508)
			(layers "F.Cu" "F.Mask" "F.Paste")
			(net "Net_243")
			(options
				(clearance outline)
				(anchor circle)
			)
			(primitives
				(gr_poly
					(pts
						(arc
							(start -0.254 0.1016)
							(mid -0.3556 0)
							(end -0.254 -0.1016)
						)
						(xy 0.3556 -0.1016) (xy 0.3556 0.1016)
					)
					(width 0)
					(fill yes)
				)
			)
		)
		(pad "27" smd custom
			(at 2.4511 -0.599948 90)
			(size 0.0508 0.0508)
			(layers "F.Cu" "F.Mask" "F.Paste")
			(net "GND")
			(options
				(clearance outline)
				(anchor circle)
			)
			(primitives
				(gr_poly
					(pts
						(arc
							(start -0.254 0.1016)
							(mid -0.3556 0)
							(end -0.254 -0.1016)
						)
						(xy 0.3556 -0.1016) (xy 0.3556 0.1016)
					)
					(width 0)
					(fill yes)
				)
			)
		)
		(pad "28" smd custom
			(at 2.4511 -0.999998 90)
			(size 0.0508 0.0508)
			(layers "F.Cu" "F.Mask" "F.Paste")
			(net "Net_348")
			(options
				(clearance outline)
				(anchor circle)
			)
			(primitives
				(gr_poly
					(pts
						(arc
							(start -0.254 0.1016)
							(mid -0.3556 0)
							(end -0.254 -0.1016)
						)
						(xy 0.3556 -0.1016) (xy 0.3556 0.1016)
					)
					(width 0)
					(fill yes)
				)
			)
		)
		(pad "29" smd custom
			(at 2.4511 -1.400048 90)
			(size 0.0508 0.0508)
			(layers "F.Cu" "F.Mask" "F.Paste")
			(net "Net_229")
			(options
				(clearance outline)
				(anchor circle)
			)
			(primitives
				(gr_poly
					(pts
						(arc
							(start -0.254 0.1016)
							(mid -0.3556 0)
							(end -0.254 -0.1016)
						)
						(xy 0.3556 -0.1016) (xy 0.3556 0.1016)
					)
					(width 0)
					(fill yes)
				)
			)
		)
		(pad "30" smd custom
			(at 2.4511 -1.800098 90)
			(size 0.0508 0.0508)
			(layers "F.Cu" "F.Mask" "F.Paste")
			(net "Net_228")
			(options
				(clearance outline)
				(anchor circle)
			)
			(primitives
				(gr_poly
					(pts
						(arc
							(start -0.254 0.1016)
							(mid -0.3556 0)
							(end -0.254 -0.1016)
						)
						(xy 0.3556 -0.1016) (xy 0.3556 0.1016)
					)
					(width 0)
					(fill yes)
				)
			)
		)
		(pad "31" smd custom
			(at 1.800098 -2.4511 90)
			(size 0.0508 0.0508)
			(layers "F.Cu" "F.Mask" "F.Paste")
			(net "Net_226")
			(options
				(clearance outline)
				(anchor circle)
			)
			(primitives
				(gr_poly
					(pts
						(arc
							(start 0.1016 0.254)
							(mid 0 0.3556)
							(end -0.1016 0.254)
						)
						(xy -0.1016 -0.3556) (xy 0.1016 -0.3556)
					)
					(width 0)
					(fill yes)
				)
			)
		)
		(pad "32" smd custom
			(at 1.400048 -2.4511 90)
			(size 0.0508 0.0508)
			(layers "F.Cu" "F.Mask" "F.Paste")
			(net "GND")
			(options
				(clearance outline)
				(anchor circle)
			)
			(primitives
				(gr_poly
					(pts
						(arc
							(start 0.1016 0.254)
							(mid 0 0.3556)
							(end -0.1016 0.254)
						)
						(xy -0.1016 -0.3556) (xy 0.1016 -0.3556)
					)
					(width 0)
					(fill yes)
				)
			)
		)
		(pad "33" smd custom
			(at 0.999998 -2.4511 90)
			(size 0.0508 0.0508)
			(layers "F.Cu" "F.Mask" "F.Paste")
			(net "VR_PVDDQ_DEF_XADDR2")
			(options
				(clearance outline)
				(anchor circle)
			)
			(primitives
				(gr_poly
					(pts
						(arc
							(start 0.1016 0.254)
							(mid 0 0.3556)
							(end -0.1016 0.254)
						)
						(xy -0.1016 -0.3556) (xy 0.1016 -0.3556)
					)
					(width 0)
					(fill yes)
				)
			)
		)
		(pad "34" smd custom
			(at 0.599948 -2.4511 90)
			(size 0.0508 0.0508)
			(layers "F.Cu" "F.Mask" "F.Paste")
			(net "Net_227")
			(options
				(clearance outline)
				(anchor circle)
			)
			(primitives
				(gr_poly
					(pts
						(arc
							(start 0.1016 0.254)
							(mid 0 0.3556)
							(end -0.1016 0.254)
						)
						(xy -0.1016 -0.3556) (xy 0.1016 -0.3556)
					)
					(width 0)
					(fill yes)
				)
			)
		)
		(pad "35" smd custom
			(at 0.199898 -2.4511 90)
			(size 0.0508 0.0508)
			(layers "F.Cu" "F.Mask" "F.Paste")
			(net "A_TSENSE_PVDDQ_DEF")
			(options
				(clearance outline)
				(anchor circle)
			)
			(primitives
				(gr_poly
					(pts
						(arc
							(start 0.1016 0.254)
							(mid 0 0.3556)
							(end -0.1016 0.254)
						)
						(xy -0.1016 -0.3556) (xy 0.1016 -0.3556)
					)
					(width 0)
					(fill yes)
				)
			)
		)
		(pad "36" smd custom
			(at -0.199898 -2.4511 90)
			(size 0.0508 0.0508)
			(layers "F.Cu" "F.Mask" "F.Paste")
			(net "VR_PVDDQ_DEF_XADDR1")
			(options
				(clearance outline)
				(anchor circle)
			)
			(primitives
				(gr_poly
					(pts
						(arc
							(start 0.1016 0.254)
							(mid 0 0.3556)
							(end -0.1016 0.254)
						)
						(xy -0.1016 -0.3556) (xy 0.1016 -0.3556)
					)
					(width 0)
					(fill yes)
				)
			)
		)
		(pad "37" smd custom
			(at -0.599948 -2.4511 90)
			(size 0.0508 0.0508)
			(layers "F.Cu" "F.Mask" "F.Paste")
			(net "VR_PVDDQ_DEF_VINSEN")
			(options
				(clearance outline)
				(anchor circle)
			)
			(primitives
				(gr_poly
					(pts
						(arc
							(start 0.1016 0.254)
							(mid 0 0.3556)
							(end -0.1016 0.254)
						)
						(xy -0.1016 -0.3556) (xy 0.1016 -0.3556)
					)
					(width 0)
					(fill yes)
				)
			)
		)
		(pad "38" smd custom
			(at -0.999998 -2.4511 90)
			(size 0.0508 0.0508)
			(layers "F.Cu" "F.Mask" "F.Paste")
			(net "VR_PVDDQ_DEF_AIINSEN")
			(options
				(clearance outline)
				(anchor circle)
			)
			(primitives
				(gr_poly
					(pts
						(arc
							(start 0.1016 0.254)
							(mid 0 0.3556)
							(end -0.1016 0.254)
						)
						(xy -0.1016 -0.3556) (xy 0.1016 -0.3556)
					)
					(width 0)
					(fill yes)
				)
			)
		)
		(pad "39" smd custom
			(at -1.400048 -2.4511 90)
			(size 0.0508 0.0508)
			(layers "F.Cu" "F.Mask" "F.Paste")
			(net "VR_PVDDQ_DEF_VDD")
			(options
				(clearance outline)
				(anchor circle)
			)
			(primitives
				(gr_poly
					(pts
						(arc
							(start 0.1016 0.254)
							(mid 0 0.3556)
							(end -0.1016 0.254)
						)
						(xy -0.1016 -0.3556) (xy 0.1016 -0.3556)
					)
					(width 0)
					(fill yes)
				)
			)
		)
		(pad "40" smd custom
			(at -1.800098 -2.4511 90)
			(size 0.0508 0.0508)
			(layers "F.Cu" "F.Mask" "F.Paste")
			(net "VR_PVDDQ_DEF_VD12")
			(options
				(clearance outline)
				(anchor circle)
			)
			(primitives
				(gr_poly
					(pts
						(arc
							(start 0.1016 0.254)
							(mid 0 0.3556)
							(end -0.1016 0.254)
						)
						(xy -0.1016 -0.3556) (xy 0.1016 -0.3556)
					)
					(width 0)
					(fill yes)
				)
			)
		)
		(pad "41" smd rect
			(at 0 0 90)
			(size 3.683 3.683)
			(layers "F.Cu" "F.Mask" "F.Paste")
			(net "GND")
		)
	)
)
